# S9S_MB_2U (Grand Teton) — schematic netlist excerpt (pin names and nets, part order shuffled) for the footprints in the layout excerpt that follows; sources: Cadence DE-HDL packaged netlist, KiCad conversion of 03242023_DA0F0TMBIJ0_F0T_Motherboard_J_brd_V01_OCP.brd

PR3963  Q_RES  25.5K 1% CHIP  pkg 0402LF  page 192 : A = P3V3_AUX ; B = P3V3_E1S_UV_0
R1420  Q_RES  2K 1% CHIP  pkg 0402LF  page 219 : A = RST_PLTRST_PLD_B_N ; B = GND

(kicad_pcb
	(version 20260206)
	(generator "pcbnew")
	(generator_version "10.0")
	(general
		(thickness 1.6)
		(legacy_teardrops no)
	)
	(paper "A4")
	(title_block
		(title "03242023_DA0F0TMBIJ0_F0T_Motherboard_J_brd_V01_OCP.brd")
		(comment 1 "Grand Teton / footprints 673-674 of 6105")
	)
	(layers
		(0 "F.Cu" signal "TOP")
		(4 "In1.Cu" signal "GND")
		(6 "In2.Cu" signal "IN1")
		(8 "In3.Cu" signal "GND1")
		(10 "In4.Cu" signal "IN2")
		(12 "In5.Cu" signal "GND2")
		(14 "In6.Cu" signal "IN3")
		(16 "In7.Cu" signal "GND3")
		(18 "In8.Cu" signal "VCC")
		(20 "In9.Cu" signal "VCC1")
		(22 "In10.Cu" signal "GND4")
		(24 "In11.Cu" signal "IN4")
		(26 "In12.Cu" signal "GND5")
		(28 "In13.Cu" signal "IN5")
		(30 "In14.Cu" signal "GND6")
		(32 "In15.Cu" signal "IN6")
		(34 "In16.Cu" signal "GND7")
		(2 "B.Cu" signal "BOTTOM")
		(9 "F.Adhes" user "F.Adhesive")
		(11 "B.Adhes" user "B.Adhesive")
		(13 "F.Paste" user "Package Geometry/Pastemask Top")
		(15 "B.Paste" user "Package Geometry/Pastemask Bottom")
		(5 "F.SilkS" user "Ref Des/Silkscreen Top")
		(7 "B.SilkS" user "Ref Des/Silkscreen Bottom")
		(1 "F.Mask" user "Board Geometry/Soldermask Top")
		(3 "B.Mask" user "Board Geometry/Soldermask Bottom")
		(17 "Dwgs.User" user "User.Drawings")
		(19 "Cmts.User" user "User.Comments")
		(21 "Eco1.User" user "User.Eco1")
		(23 "Eco2.User" user "User.Eco2")
		(25 "Edge.Cuts" user "Board Geometry/Outline")
		(27 "Margin" user)
		(31 "F.CrtYd" user "Package Geometry/Place Bound Top")
		(29 "B.CrtYd" user "Package Geometry/Place Bound Bottom")
		(35 "F.Fab" user "Ref Des/Assembly Top")
		(33 "B.Fab" user "Ref Des/Assembly Bottom")
	)
	(footprint ""
		(layer "F.Cu")
		(at 193.38036 -118.074948)
		(property "Reference" "R1420"
			(at 0 0 0)
			(layer "F.SilkS")
			(hide yes)
			(effects
				(font
					(size 1.27 1.27)
				)
			)
		)
		(property "Value" ""
			(at 0 0 0)
			(layer "F.Fab")
			(effects
				(font
					(size 1.27 1.27)
				)
			)
		)
		(duplicate_pad_numbers_are_jumpers no)
		(fp_line
			(start -0.7874 -0.4064)
			(end 0.7874 -0.4064)
			(stroke
				(width 0.1524)
				(type default)
			)
			(layer "F.SilkS")
		)
		(fp_line
			(start -0.7874 0.4064)
			(end -0.7874 -0.4064)
			(stroke
				(width 0.1524)
				(type default)
			)
			(layer "F.SilkS")
		)
		(fp_line
			(start 0.7874 -0.4064)
			(end 0.7874 0.4064)
			(stroke
				(width 0.1524)
				(type default)
			)
			(layer "F.SilkS")
		)
		(fp_line
			(start 0.7874 0.4064)
			(end -0.7874 0.4064)
			(stroke
				(width 0.1524)
				(type default)
			)
			(layer "F.SilkS")
		)
		(fp_line
			(start -0.67945 -0.305054)
			(end -0.12065 -0.305054)
			(stroke
				(width 0.1)
				(type default)
			)
			(layer "F.Fab")
		)
		(fp_line
			(start -0.67945 0.3048)
			(end -0.67945 -0.305054)
			(stroke
				(width 0.1)
				(type default)
			)
			(layer "F.Fab")
		)
		(fp_line
			(start -0.12065 -0.305054)
			(end -0.12065 -0.2794)
			(stroke
				(width 0.1)
				(type default)
			)
			(layer "F.Fab")
		)
		(fp_line
			(start -0.12065 -0.2794)
			(end 0.12065 -0.2794)
			(stroke
				(width 0.1)
				(type default)
			)
			(layer "F.Fab")
		)
		(fp_line
			(start -0.12065 0.2794)
			(end -0.12065 0.3048)
			(stroke
				(width 0.1)
				(type default)
			)
			(layer "F.Fab")
		)
		(fp_line
			(start -0.12065 0.3048)
			(end -0.67945 0.3048)
			(stroke
				(width 0.1)
				(type default)
			)
			(layer "F.Fab")
		)
		(fp_line
			(start 0.120396 0.2794)
			(end -0.12065 0.2794)
			(stroke
				(width 0.1)
				(type default)
			)
			(layer "F.Fab")
		)
		(fp_line
			(start 0.120396 0.3048)
			(end 0.120396 0.2794)
			(stroke
				(width 0.1)
				(type default)
			)
			(layer "F.Fab")
		)
		(fp_line
			(start 0.12065 -0.3048)
			(end 0.67945 -0.3048)
			(stroke
				(width 0.1)
				(type default)
			)
			(layer "F.Fab")
		)
		(fp_line
			(start 0.12065 -0.2794)
			(end 0.12065 -0.3048)
			(stroke
				(width 0.1)
				(type default)
			)
			(layer "F.Fab")
		)
		(fp_line
			(start 0.67945 -0.3048)
			(end 0.67945 0.3048)
			(stroke
				(width 0.1)
				(type default)
			)
			(layer "F.Fab")
		)
		(fp_line
			(start 0.67945 0.3048)
			(end 0.120396 0.3048)
			(stroke
				(width 0.1)
				(type default)
			)
			(layer "F.Fab")
		)
		(pad "1" smd circle
			(at -0.40005 0)
			(size 0 0)
			(layers "F.Cu" "F.Mask" "F.Paste")
			(net "RST_PLTRST_PLD_B_N")
		)
		(pad "2" smd circle
			(at 0.40005 0)
			(size 0 0)
			(layers "F.Cu" "F.Mask" "F.Paste")
			(net "GND")
		)
	)
	(footprint ""
		(layer "F.Cu")
		(at 217.881962 -68.340478)
		(property "Reference" "PR3963"
			(at 0 0 0)
			(layer "F.SilkS")
			(hide yes)
			(effects
				(font
					(size 1.27 1.27)
				)
			)
		)
		(property "Value" ""
			(at 0 0 0)
			(layer "F.Fab")
			(effects
				(font
					(size 1.27 1.27)
				)
			)
		)
		(duplicate_pad_numbers_are_jumpers no)
		(fp_line
			(start -0.7874 -0.4064)
			(end 0.7874 -0.4064)
			(stroke
				(width 0.1524)
				(type default)
			)
			(layer "F.SilkS")
		)
		(fp_line
			(start -0.7874 0.4064)
			(end -0.7874 -0.4064)
			(stroke
				(width 0.1524)
				(type default)
			)
			(layer "F.SilkS")
		)
		(fp_line
			(start 0.7874 -0.4064)
			(end 0.7874 0.4064)
			(stroke
				(width 0.1524)
				(type default)
			)
			(layer "F.SilkS")
		)
		(fp_line
			(start 0.7874 0.4064)
			(end -0.7874 0.4064)
			(stroke
				(width 0.1524)
				(type default)
			)
			(layer "F.SilkS")
		)
		(fp_line
			(start -0.67945 -0.305054)
			(end -0.12065 -0.305054)
			(stroke
				(width 0.1)
				(type default)
			)
			(layer "F.Fab")
		)
		(fp_line
			(start -0.67945 0.3048)
			(end -0.67945 -0.305054)
			(stroke
				(width 0.1)
				(type default)
			)
			(layer "F.Fab")
		)
		(fp_line
			(start -0.12065 -0.305054)
			(end -0.12065 -0.2794)
			(stroke
				(width 0.1)
				(type default)
			)
			(layer "F.Fab")
		)
		(fp_line
			(start -0.12065 -0.2794)
			(end 0.12065 -0.2794)
			(stroke
				(width 0.1)
				(type default)
			)
			(layer "F.Fab")
		)
		(fp_line
			(start -0.12065 0.2794)
			(end -0.12065 0.3048)
			(stroke
				(width 0.1)
				(type default)
			)
			(layer "F.Fab")
		)
		(fp_line
			(start -0.12065 0.3048)
			(end -0.67945 0.3048)
			(stroke
				(width 0.1)
				(type default)
			)
			(layer "F.Fab")
		)
		(fp_line
			(start 0.120396 0.2794)
			(end -0.12065 0.2794)
			(stroke
				(width 0.1)
				(type default)
			)
			(layer "F.Fab")
		)
		(fp_line
			(start 0.120396 0.3048)
			(end 0.120396 0.2794)
			(stroke
				(width 0.1)
				(type default)
			)
			(layer "F.Fab")
		)
		(fp_line
			(start 0.12065 -0.3048)
			(end 0.67945 -0.3048)
			(stroke
				(width 0.1)
				(type default)
			)
			(layer "F.Fab")
		)
		(fp_line
			(start 0.12065 -0.2794)
			(end 0.12065 -0.3048)
			(stroke
				(width 0.1)
				(type default)
			)
			(layer "F.Fab")
		)
		(fp_line
			(start 0.67945 -0.3048)
			(end 0.67945 0.3048)
			(stroke
				(width 0.1)
				(type default)
			)
			(layer "F.Fab")
		)
		(fp_line
			(start 0.67945 0.3048)
			(end 0.120396 0.3048)
			(stroke
				(width 0.1)
				(type default)
			)
			(layer "F.Fab")
		)
		(pad "1" smd circle
			(at -0.40005 0)
			(size 0 0)
			(layers "F.Cu" "F.Mask" "F.Paste")
			(net "P3V3_AUX")
		)
		(pad "2" smd circle
			(at 0.40005 0)
			(size 0 0)
			(layers "F.Cu" "F.Mask" "F.Paste")
			(net "P3V3_E1S_UV_0")
		)
	)
)
